#ISCELL
  mstr_misc dns *
  *
#ISCELL
  pure_quanta quanta_title_block_c *
  *
#CELL
  pure_quanta q_cap *
  page285_i1
#CELL
  pure_quanta q_res *
  page285_i10
#CELL
  pure_quanta q_cap *
  page285_i11
#ISCELL
  logical_power universal_gnd *
  page285_i12
#CELL
  pure_quanta q_res *
  page285_i13
#CELL
  pure_quanta q_res *
  page285_i14
#CELL
  pure_quanta q_cap *
  page285_i15
#CELL
  pure_quanta q_cap *
  page285_i16
#CELL
  pure_quanta q_cap *
  page285_i17
#CELL
  pure_quanta q_res *
  page285_i18
#ISCELL
  logical_power universal_gnd *
  page285_i19
#ISCELL
  logical_power universal_gnd *
  page285_i2
#ISCELL
  logical_power vccaux15 *
  page285_i20
#ISCELL
  logical_power universal_gnd *
  page285_i21
#ISCELL
  logical_power universal_gnd *
  page285_i22
#CELL
  pure_quanta q_cap *
  page285_i23
#CELL
  pure_quanta q_cap *
  page285_i24
#CELL
  pure_quanta rs53318lr *
  page285_i25
#CELL
  pure_quanta q_cap *
  page285_i26
#CELL
  pure_quanta q_res *
  page285_i27
#CELL
  pure_quanta q_res *
  page285_i28
#CELL
  pure_quanta mosfet_n *
  page285_i29
#CELL
  pure_quanta q_res *
  page285_i3
#CELL
  pure_quanta q_res *
  page285_i30
#ISCELL
  standard offpage *
  page285_i31
#CELL
  pure_quanta q_cap *
  page285_i32
#CELL
  pure_quanta q_inductor *
  page285_i33
#CELL
  pure_quanta q_res *
  page285_i34
#CELL
  pure_quanta q_cap *
  page285_i35
#CELL
  pure_quanta q_cap *
  page285_i36
#CELL
  pure_quanta q_res *
  page285_i37
#ISCELL
  logical_power universal_gnd *
  page285_i38
#CELL
  pure_quanta q_cap *
  page285_i39
#ISCELL
  standard offpage *
  page285_i4
#CELL
  pure_quanta q_cap *
  page285_i40
#CELL
  pure_quanta q_cap *
  page285_i41
#ISCELL
  standard offpage *
  page285_i42
#ISCELL
  logical_power universal_power *
  page285_i43
#CELL
  pure_quanta q_short *
  page285_i44
#ISCELL
  logical_power universal_gnd *
  page285_i45
#CELL
  pure_quanta q_short *
  page285_i46
#CELL
  pure_quanta q_cap *
  page285_i47
#ISCELL
  logical_power universal_gnd *
  page285_i48
#CELL
  pure_quanta q_capp *
  page285_i49
#ISCELL
  logical_power universal_power *
  page285_i5
#ISCELL
  logical_power universal_power *
  page285_i50
#ISCELL
  logical_power vccaux15 *
  page285_i6
#ISCELL
  logical_power universal_gnd *
  page285_i7
#CELL
  pure_quanta q_cap *
  page285_i8
#ISCELL
  logical_power universal_gnd *
  page285_i9
